(kicad_pcb
	(version 20260206)
	(generator "pcbnew")
	(generator_version "10.0")
	(general
		(thickness 1.6)
		(legacy_teardrops no)
	)
	(paper "A4")
	(title_block
		(title "Wiwynn_Tioga_Pass_MB.brd")
		(comment 1 "Tioga Pass / footprints 3312-3318 of 4770")
	)
	(layers
		(0 "F.Cu" signal "TOP")
		(4 "In1.Cu" signal "L2GND")
		(6 "In2.Cu" signal "L3")
		(8 "In3.Cu" signal "L4GND")
		(10 "In4.Cu" signal "L5")
		(12 "In5.Cu" signal "L6GND")
		(14 "In6.Cu" signal "L7VCC")
		(16 "In7.Cu" signal "L8VCC")
		(18 "In8.Cu" signal "L9GND")
		(20 "In9.Cu" signal "L10")
		(22 "In10.Cu" signal "L11GND")
		(24 "In11.Cu" signal "L12")
		(26 "In12.Cu" signal "L13GND")
		(2 "B.Cu" signal "BOTTOM")
		(9 "F.Adhes" user "F.Adhesive")
		(11 "B.Adhes" user "B.Adhesive")
		(13 "F.Paste" user "Package Geometry/Pastemask Top")
		(15 "B.Paste" user "Package Geometry/Pastemask Bottom")
		(5 "F.SilkS" user "Ref Des/Silkscreen Top")
		(7 "B.SilkS" user "Ref Des/Silkscreen Bottom")
		(1 "F.Mask" user "Board Geometry/Soldermask Top")
		(3 "B.Mask" user "Board Geometry/Soldermask Bottom")
		(17 "Dwgs.User" user "User.Drawings")
		(19 "Cmts.User" user "User.Comments")
		(21 "Eco1.User" user "User.Eco1")
		(23 "Eco2.User" user "User.Eco2")
		(25 "Edge.Cuts" user "Board Geometry/Outline")
		(27 "Margin" user)
		(31 "F.CrtYd" user "Package Geometry/Place Bound Top")
		(29 "B.CrtYd" user "Package Geometry/Place Bound Bottom")
		(35 "F.Fab" user "Ref Des/Assembly Top")
		(33 "B.Fab" user "Ref Des/Assembly Bottom")
	)
	(footprint ""
		(layer "B.Cu")
		(at 169.545 -73.4822 180)
		(property "Reference" "R6P25"
			(at 0 0 0)
			(layer "B.SilkS")
			(hide yes)
			(effects
				(font
					(size 1.27 1.27)
				)
				(justify mirror)
			)
		)
		(property "Value" ""
			(at 0 0 0)
			(layer "B.Fab")
			(effects
				(font
					(size 1.27 1.27)
				)
				(justify mirror)
			)
		)
		(duplicate_pad_numbers_are_jumpers no)
		(fp_poly
			(pts
				(xy 0.4953 -0.2032) (xy -0.4953 -0.2032) (xy -0.4953 1.6002) (xy 0.4953 1.6002)
			)
			(stroke
				(width 0)
				(type default)
			)
			(fill no)
			(layer "B.CrtYd")
		)
		(fp_line
			(start 0.4953 1.6002)
			(end 0.4953 -0.2032)
			(stroke
				(width 0.1)
				(type default)
			)
			(layer "B.Fab")
		)
		(fp_line
			(start 0.4953 -0.2032)
			(end -0.4953 -0.2032)
			(stroke
				(width 0.1)
				(type default)
			)
			(layer "B.Fab")
		)
		(fp_line
			(start -0.4953 1.6002)
			(end 0.4953 1.6002)
			(stroke
				(width 0.1)
				(type default)
			)
			(layer "B.Fab")
		)
		(fp_line
			(start -0.4953 -0.2032)
			(end -0.4953 1.6002)
			(stroke
				(width 0.1)
				(type default)
			)
			(layer "B.Fab")
		)
		(pad "1" smd rect
			(at 0 0)
			(size 0.762 0.889)
			(layers "B.Cu" "B.Mask" "B.Paste")
			(net "P3V3_DB1200")
		)
		(pad "2" smd rect
			(at 0 1.397)
			(size 0.762 0.889)
			(layers "B.Cu" "B.Mask" "B.Paste")
			(net "P3V3_DB1200_R")
		)
		(zone
			(layer "B.Cu")
			(hatch none 0.5)
			(connect_pads
				(clearance 0)
			)
			(min_thickness 0.25)
			(keepout
				(tracks not_allowed)
				(vias allowed)
				(pads allowed)
				(copperpour not_allowed)
				(footprints allowed)
			)
			(placement
				(enabled no)
				(sheetname "")
			)
			(fill
				(thermal_gap 0.5)
				(thermal_bridge_width 0.5)
				(island_removal_mode 0)
			)
			(polygon
				(pts
					(xy 169.164 -74.4347) (xy 169.164 -73.9267) (xy 169.926 -73.9267) (xy 169.926 -74.4347)
				)
			)
		)
		(zone
			(layer "B.Cu")
			(hatch none 0.5)
			(connect_pads
				(clearance 0)
			)
			(min_thickness 0.25)
			(keepout
				(tracks allowed)
				(vias not_allowed)
				(pads allowed)
				(copperpour not_allowed)
				(footprints allowed)
			)
			(placement
				(enabled no)
				(sheetname "")
			)
			(fill
				(thermal_gap 0.5)
				(thermal_bridge_width 0.5)
				(island_removal_mode 0)
			)
			(polygon
				(pts
					(xy 169.926 -74.4347) (xy 169.926 -73.9267) (xy 169.164 -73.9267) (xy 169.164 -74.4347)
				)
			)
		)
	)
	(footprint ""
		(layer "B.Cu")
		(at 1.3462 -139.446 90)
		(property "Reference" "C9L6"
			(at 0 0 90)
			(layer "B.SilkS")
			(hide yes)
			(effects
				(font
					(size 1.27 1.27)
				)
				(justify mirror)
			)
		)
		(property "Value" ""
			(at 0 0 90)
			(layer "B.Fab")
			(effects
				(font
					(size 1.27 1.27)
				)
				(justify mirror)
			)
		)
		(duplicate_pad_numbers_are_jumpers no)
		(fp_rect
			(start -0.7239 -0.2159)
			(end 0.7239 1.9939)
			(stroke
				(width 0)
				(type default)
			)
			(fill no)
			(layer "B.CrtYd")
		)
		(fp_line
			(start 0.7239 -0.2159)
			(end 0.7239 1.9939)
			(stroke
				(width 0.1)
				(type default)
			)
			(layer "B.Fab")
		)
		(fp_line
			(start -0.7239 -0.2159)
			(end 0.7239 -0.2159)
			(stroke
				(width 0.1)
				(type default)
			)
			(layer "B.Fab")
		)
		(fp_line
			(start 0.7239 1.9939)
			(end -0.7239 1.9939)
			(stroke
				(width 0.1)
				(type default)
			)
			(layer "B.Fab")
		)
		(fp_line
			(start -0.7239 1.9939)
			(end -0.7239 -0.2159)
			(stroke
				(width 0.1)
				(type default)
			)
			(layer "B.Fab")
		)
		(pad "1" smd rect
			(at 0 0 270)
			(size 1.27 1.016)
			(layers "B.Cu" "B.Mask" "B.Paste")
			(net "VR_FET_SW_P12V_STBY_PVDDQ_KLM")
		)
		(pad "2" smd rect
			(at 0 1.778 270)
			(size 1.27 1.016)
			(layers "B.Cu" "B.Mask" "B.Paste")
			(net "GND")
		)
		(zone
			(layer "B.Cu")
			(hatch none 0.5)
			(connect_pads
				(clearance 0)
			)
			(min_thickness 0.25)
			(keepout
				(tracks not_allowed)
				(vias allowed)
				(pads allowed)
				(copperpour not_allowed)
				(footprints allowed)
			)
			(placement
				(enabled no)
				(sheetname "")
			)
			(fill
				(thermal_gap 0.5)
				(thermal_bridge_width 0.5)
				(island_removal_mode 0)
			)
			(polygon
				(pts
					(xy 1.8542 -138.811) (xy 2.6162 -138.811) (xy 2.6162 -140.081) (xy 1.8542 -140.081)
				)
			)
		)
	)
	(footprint ""
		(layer "B.Cu")
		(at 188.22797 -60.461144 180)
		(property "Reference" "C22W21"
			(at 0 0 0)
			(layer "B.SilkS")
			(hide yes)
			(effects
				(font
					(size 1.27 1.27)
				)
				(justify mirror)
			)
		)
		(property "Value" "*"
			(at 0.0762 -6.2357 180)
			(unlocked yes)
			(layer "B.Fab")
			(hide yes)
			(effects
				(font
					(size 1.27 1.016)
					(thickness 0.1524)
				)
				(justify mirror)
			)
		)
		(property "Device Type" "SC22U16V5MX-4-GP_SMD-BCG5-SC22A"
			(at 0.0762 -8.2677 180)
			(unlocked yes)
			(layer "B.Fab")
			(hide yes)
			(effects
				(font
					(size 1.27 1.016)
					(thickness 0.1524)
				)
				(justify mirror)
			)
		)
		(duplicate_pad_numbers_are_jumpers no)
		(fp_line
			(start -0.635 0)
			(end 0.635 0)
			(stroke
				(width 0.508)
				(type default)
			)
			(layer "B.SilkS")
		)
		(fp_rect
			(start 0.9652 1.778)
			(end -0.9652 -1.778)
			(stroke
				(width 0)
				(type default)
			)
			(fill no)
			(layer "B.CrtYd")
		)
		(fp_poly
			(pts
				(xy 0.9652 -1.778) (xy -0.9652 -1.778) (xy -0.9652 1.778) (xy 0.9652 1.778)
			)
			(stroke
				(width 0)
				(type default)
			)
			(fill no)
			(layer "B.Fab")
		)
		(pad "1" smd rect
			(at 0 -0.9652)
			(size 1.397 1.143)
			(layers "B.Cu" "B.Mask" "B.Paste")
			(net "VR_FET_SW_P12V_STBY_PVCCIN_CPU0")
		)
		(pad "2" smd rect
			(at 0 0.9652)
			(size 1.397 1.143)
			(layers "B.Cu" "B.Mask" "B.Paste")
			(net "GND")
		)
	)
	(footprint ""
		(layer "B.Cu")
		(at 386.309616 -13.04417)
		(property "Reference" "R32W12"
			(at 0.8382 -0.67818 0)
			(unlocked yes)
			(layer "B.SilkS")
			(effects
				(font
					(size 0.4064 0.254)
					(thickness 0.1524)
				)
				(justify left mirror)
			)
		)
		(property "Value" ""
			(at 0 0 0)
			(layer "B.Fab")
			(effects
				(font
					(size 1.27 1.27)
				)
				(justify mirror)
			)
		)
		(duplicate_pad_numbers_are_jumpers no)
		(fp_poly
			(pts
				(xy 0.2794 -0.1016) (xy -0.2794 -0.1016) (xy -0.2794 0.9906) (xy 0.2794 0.9906)
			)
			(stroke
				(width 0)
				(type default)
			)
			(fill no)
			(layer "B.CrtYd")
		)
		(fp_line
			(start -0.2794 -0.1016)
			(end 0.2794 -0.1016)
			(stroke
				(width 0.1)
				(type default)
			)
			(layer "B.Fab")
		)
		(fp_line
			(start -0.2794 0.9906)
			(end -0.2794 -0.1016)
			(stroke
				(width 0.1)
				(type default)
			)
			(layer "B.Fab")
		)
		(fp_line
			(start 0.2794 -0.1016)
			(end 0.2794 0.9906)
			(stroke
				(width 0.1)
				(type default)
			)
			(layer "B.Fab")
		)
		(fp_line
			(start 0.2794 0.9906)
			(end -0.2794 0.9906)
			(stroke
				(width 0.1)
				(type default)
			)
			(layer "B.Fab")
		)
		(pad "1" smd rect
			(at 0 0 180)
			(size 0.508 0.508)
			(layers "B.Cu" "B.Mask" "B.Paste")
			(net "SMB_M2_ALT_N")
		)
		(pad "2" smd rect
			(at 0 0.889 180)
			(size 0.508 0.508)
			(layers "B.Cu" "B.Mask" "B.Paste")
			(net "SMB_M2_ALT_R_N")
		)
		(zone
			(layer "B.Cu")
			(hatch none 0.5)
			(connect_pads
				(clearance 0)
			)
			(min_thickness 0.25)
			(keepout
				(tracks allowed)
				(vias not_allowed)
				(pads allowed)
				(copperpour not_allowed)
				(footprints allowed)
			)
			(placement
				(enabled no)
				(sheetname "")
			)
			(fill
				(thermal_gap 0.5)
				(thermal_bridge_width 0.5)
				(island_removal_mode 0)
			)
			(polygon
				(pts
					(xy 386.563616 -12.79017) (xy 386.055616 -12.79017) (xy 386.055616 -12.40917) (xy 386.563616 -12.40917)
				)
			)
		)
		(zone
			(layer "B.Cu")
			(hatch none 0.5)
			(connect_pads
				(clearance 0)
			)
			(min_thickness 0.25)
			(keepout
				(tracks not_allowed)
				(vias allowed)
				(pads allowed)
				(copperpour not_allowed)
				(footprints allowed)
			)
			(placement
				(enabled no)
				(sheetname "")
			)
			(fill
				(thermal_gap 0.5)
				(thermal_bridge_width 0.5)
				(island_removal_mode 0)
			)
			(polygon
				(pts
					(xy 386.563616 -12.40917) (xy 386.055616 -12.40917) (xy 386.055616 -12.79017) (xy 386.563616 -12.79017)
				)
			)
		)
	)
	(footprint ""
		(layer "B.Cu")
		(at 393.9667 -10.01903 180)
		(property "Reference" "R32W10"
			(at 0.8382 -0.67818 180)
			(unlocked yes)
			(layer "B.SilkS")
			(effects
				(font
					(size 0.4064 0.254)
					(thickness 0.1524)
				)
				(justify left mirror)
			)
		)
		(property "Value" ""
			(at 0 0 0)
			(layer "B.Fab")
			(effects
				(font
					(size 1.27 1.27)
				)
				(justify mirror)
			)
		)
		(duplicate_pad_numbers_are_jumpers no)
		(fp_poly
			(pts
				(xy 0.2794 -0.1016) (xy -0.2794 -0.1016) (xy -0.2794 0.9906) (xy 0.2794 0.9906)
			)
			(stroke
				(width 0)
				(type default)
			)
			(fill no)
			(layer "B.CrtYd")
		)
		(fp_line
			(start 0.2794 0.9906)
			(end -0.2794 0.9906)
			(stroke
				(width 0.1)
				(type default)
			)
			(layer "B.Fab")
		)
		(fp_line
			(start 0.2794 -0.1016)
			(end 0.2794 0.9906)
			(stroke
				(width 0.1)
				(type default)
			)
			(layer "B.Fab")
		)
		(fp_line
			(start -0.2794 0.9906)
			(end -0.2794 -0.1016)
			(stroke
				(width 0.1)
				(type default)
			)
			(layer "B.Fab")
		)
		(fp_line
			(start -0.2794 -0.1016)
			(end 0.2794 -0.1016)
			(stroke
				(width 0.1)
				(type default)
			)
			(layer "B.Fab")
		)
		(pad "1" smd rect
			(at 0 0)
			(size 0.508 0.508)
			(layers "B.Cu" "B.Mask" "B.Paste")
			(net "SMB_M2_SCL")
		)
		(pad "2" smd rect
			(at 0 0.889)
			(size 0.508 0.508)
			(layers "B.Cu" "B.Mask" "B.Paste")
			(net "SMB_M2_SCL_R")
		)
		(zone
			(layer "B.Cu")
			(hatch none 0.5)
			(connect_pads
				(clearance 0)
			)
			(min_thickness 0.25)
			(keepout
				(tracks not_allowed)
				(vias allowed)
				(pads allowed)
				(copperpour not_allowed)
				(footprints allowed)
			)
			(placement
				(enabled no)
				(sheetname "")
			)
			(fill
				(thermal_gap 0.5)
				(thermal_bridge_width 0.5)
				(island_removal_mode 0)
			)
			(polygon
				(pts
					(xy 393.7127 -10.65403) (xy 394.2207 -10.65403) (xy 394.2207 -10.27303) (xy 393.7127 -10.27303)
				)
			)
		)
		(zone
			(layer "B.Cu")
			(hatch none 0.5)
			(connect_pads
				(clearance 0)
			)
			(min_thickness 0.25)
			(keepout
				(tracks allowed)
				(vias not_allowed)
				(pads allowed)
				(copperpour not_allowed)
				(footprints allowed)
			)
			(placement
				(enabled no)
				(sheetname "")
			)
			(fill
				(thermal_gap 0.5)
				(thermal_bridge_width 0.5)
				(island_removal_mode 0)
			)
			(polygon
				(pts
					(xy 393.7127 -10.27303) (xy 394.2207 -10.27303) (xy 394.2207 -10.65403) (xy 393.7127 -10.65403)
				)
			)
		)
	)
	(footprint ""
		(layer "B.Cu")
		(at 347.17736 -77.788516 180)
		(property "Reference" "C3P23"
			(at 0 0 0)
			(layer "B.SilkS")
			(hide yes)
			(effects
				(font
					(size 1.27 1.27)
				)
				(justify mirror)
			)
		)
		(property "Value" ""
			(at 0 0 0)
			(layer "B.Fab")
			(effects
				(font
					(size 1.27 1.27)
				)
				(justify mirror)
			)
		)
		(duplicate_pad_numbers_are_jumpers no)
		(fp_poly
			(pts
				(xy -0.3048 -0.1016) (xy -0.3048 0.9906) (xy 0.3048 0.9906) (xy 0.3048 -0.1016)
			)
			(stroke
				(width 0)
				(type default)
			)
			(fill no)
			(layer "B.CrtYd")
		)
		(fp_line
			(start 0.3048 0.9906)
			(end -0.3048 0.9906)
			(stroke
				(width 0.1)
				(type default)
			)
			(layer "B.Fab")
		)
		(fp_line
			(start 0.3048 -0.1016)
			(end 0.3048 0.9906)
			(stroke
				(width 0.1)
				(type default)
			)
			(layer "B.Fab")
		)
		(fp_line
			(start -0.3048 0.9906)
			(end -0.3048 -0.1016)
			(stroke
				(width 0.1)
				(type default)
			)
			(layer "B.Fab")
		)
		(fp_line
			(start -0.3048 -0.1016)
			(end 0.3048 -0.1016)
			(stroke
				(width 0.1)
				(type default)
			)
			(layer "B.Fab")
		)
		(pad "1" smd rect
			(at 0 0)
			(size 0.508 0.508)
			(layers "B.Cu" "B.Mask" "B.Paste")
			(net "P3E_CPU0_PE1_SS_TXP<3>")
		)
		(pad "2" smd rect
			(at 0 0.889)
			(size 0.508 0.508)
			(layers "B.Cu" "B.Mask" "B.Paste")
			(net "P3E_CPU0_PE1_PCH_TXP<3>")
		)
		(zone
			(layer "B.Cu")
			(hatch none 0.5)
			(connect_pads
				(clearance 0)
			)
			(min_thickness 0.25)
			(keepout
				(tracks not_allowed)
				(vias allowed)
				(pads allowed)
				(copperpour not_allowed)
				(footprints allowed)
			)
			(placement
				(enabled no)
				(sheetname "")
			)
			(fill
				(thermal_gap 0.5)
				(thermal_bridge_width 0.5)
				(island_removal_mode 0)
			)
			(polygon
				(pts
					(xy 346.92336 -78.423516) (xy 347.43136 -78.423516) (xy 347.43136 -78.042516) (xy 346.92336 -78.042516)
				)
			)
		)
		(zone
			(layer "B.Cu")
			(hatch none 0.5)
			(connect_pads
				(clearance 0)
			)
			(min_thickness 0.25)
			(keepout
				(tracks allowed)
				(vias not_allowed)
				(pads allowed)
				(copperpour not_allowed)
				(footprints allowed)
			)
			(placement
				(enabled no)
				(sheetname "")
			)
			(fill
				(thermal_gap 0.5)
				(thermal_bridge_width 0.5)
				(island_removal_mode 0)
			)
			(polygon
				(pts
					(xy 346.92336 -78.042516) (xy 347.43136 -78.042516) (xy 347.43136 -78.423516) (xy 346.92336 -78.423516)
				)
			)
		)
	)
	(footprint ""
		(layer "B.Cu")
		(at 374.1928 -53.8099 -90)
		(property "Reference" "R3P36"
			(at 0 0 90)
			(layer "B.SilkS")
			(hide yes)
			(effects
				(font
					(size 1.27 1.27)
				)
				(justify mirror)
			)
		)
		(property "Value" ""
			(at 0 0 90)
			(layer "B.Fab")
			(effects
				(font
					(size 1.27 1.27)
				)
				(justify mirror)
			)
		)
		(duplicate_pad_numbers_are_jumpers no)
		(fp_poly
			(pts
				(xy 0.2794 -0.1016) (xy -0.2794 -0.1016) (xy -0.2794 0.9906) (xy 0.2794 0.9906)
			)
			(stroke
				(width 0)
				(type default)
			)
			(fill no)
			(layer "B.CrtYd")
		)
		(fp_line
			(start -0.2794 0.9906)
			(end -0.2794 -0.1016)
			(stroke
				(width 0.1)
				(type default)
			)
			(layer "B.Fab")
		)
		(fp_line
			(start 0.2794 0.9906)
			(end -0.2794 0.9906)
			(stroke
				(width 0.1)
				(type default)
			)
			(layer "B.Fab")
		)
		(fp_line
			(start -0.2794 -0.1016)
			(end 0.2794 -0.1016)
			(stroke
				(width 0.1)
				(type default)
			)
			(layer "B.Fab")
		)
		(fp_line
			(start 0.2794 -0.1016)
			(end 0.2794 0.9906)
			(stroke
				(width 0.1)
				(type default)
			)
			(layer "B.Fab")
		)
		(pad "1" smd rect
			(at 0 0 90)
			(size 0.508 0.508)
			(layers "B.Cu" "B.Mask" "B.Paste")
			(net "P3V3_STBY")
		)
		(pad "2" smd rect
			(at 0 0.889 90)
			(size 0.508 0.508)
			(layers "B.Cu" "B.Mask" "B.Paste")
			(net "PU_GTL2014_1_DIR")
		)
		(zone
			(layer "B.Cu")
			(hatch none 0.5)
			(connect_pads
				(clearance 0)
			)
			(min_thickness 0.25)
			(keepout
				(tracks not_allowed)
				(vias allowed)
				(pads allowed)
				(copperpour not_allowed)
				(footprints allowed)
			)
			(placement
				(enabled no)
				(sheetname "")
			)
			(fill
				(thermal_gap 0.5)
				(thermal_bridge_width 0.5)
				(island_removal_mode 0)
			)
			(polygon
				(pts
					(xy 373.5578 -53.5559) (xy 373.5578 -54.0639) (xy 373.9388 -54.0639) (xy 373.9388 -53.5559)
				)
			)
		)
		(zone
			(layer "B.Cu")
			(hatch none 0.5)
			(connect_pads
				(clearance 0)
			)
			(min_thickness 0.25)
			(keepout
				(tracks allowed)
				(vias not_allowed)
				(pads allowed)
				(copperpour not_allowed)
				(footprints allowed)
			)
			(placement
				(enabled no)
				(sheetname "")
			)
			(fill
				(thermal_gap 0.5)
				(thermal_bridge_width 0.5)
				(island_removal_mode 0)
			)
			(polygon
				(pts
					(xy 373.9388 -53.5559) (xy 373.9388 -54.0639) (xy 373.5578 -54.0639) (xy 373.5578 -53.5559)
				)
			)
		)
	)
)
